# S9S_MB_2U (Grand Teton) — schematic netlist excerpt (pin names and nets, part order shuffled) for the footprints in the layout excerpt that follows; sources: Cadence DE-HDL packaged netlist, KiCad conversion of 03242023_DA0F0TMBIJ0_F0T_Motherboard_J_brd_V01_OCP.brd

PU50_P1_1  ISL99390FRZTR5935  ISL99390FRZ-TR5935 IC  pkg QFN21_6X5XB  page 293
  VOS  = PVCCINFAON_CPU1_VOS1
  AGND  = GND
  VCC  = PVCCINFAON_CPU1_VDD1
  PVCC  = PVCCFA_EHV_CPU1_PVCC
  PGND1  = GND
  GL1  = NC
  PGND2  = GND
  SW  = SW_PVCCINFAON_CPU1_SW1
  VIN1  = SW_P12V_PVCCINFAON_CPU1_FLT
  VIN2  = SW_P12V_PVCCINFAON_CPU1_FLT
  DNC  = NC
  PHASE  = SW_PVCCINFAON_CPU1_BOOTR1
  BOOT  = SW_PVCCINFAON_CPU1_BOOT1
  PWM  = PVCCINFAON_CPU1_APWM1
  EN  = PVCCINFAON_CPU1_VDD1
  TOUT_FLT  = PVCCINFAON_CPU1_ATSEN
  LSET  = PVCCINFAON_CPU1_LSET1
  IOUT  = PVCCINFAON_CPU1_ACSP1
  REFIN  = PVCCINFAON_CPU1_VREF
  PGND3  = GND
  GL2  = NC

(kicad_pcb
	(version 20260206)
	(generator "pcbnew")
	(generator_version "10.0")
	(general
		(thickness 1.6)
		(legacy_teardrops no)
	)
	(paper "A4")
	(title_block
		(title "03242023_DA0F0TMBIJ0_F0T_Motherboard_J_brd_V01_OCP.brd")
		(comment 1 "Grand Teton / footprints 3349-3349 of 6105")
	)
	(layers
		(0 "F.Cu" signal "TOP")
		(4 "In1.Cu" signal "GND")
		(6 "In2.Cu" signal "IN1")
		(8 "In3.Cu" signal "GND1")
		(10 "In4.Cu" signal "IN2")
		(12 "In5.Cu" signal "GND2")
		(14 "In6.Cu" signal "IN3")
		(16 "In7.Cu" signal "GND3")
		(18 "In8.Cu" signal "VCC")
		(20 "In9.Cu" signal "VCC1")
		(22 "In10.Cu" signal "GND4")
		(24 "In11.Cu" signal "IN4")
		(26 "In12.Cu" signal "GND5")
		(28 "In13.Cu" signal "IN5")
		(30 "In14.Cu" signal "GND6")
		(32 "In15.Cu" signal "IN6")
		(34 "In16.Cu" signal "GND7")
		(2 "B.Cu" signal "BOTTOM")
		(9 "F.Adhes" user "F.Adhesive")
		(11 "B.Adhes" user "B.Adhesive")
		(13 "F.Paste" user "Package Geometry/Pastemask Top")
		(15 "B.Paste" user "Package Geometry/Pastemask Bottom")
		(5 "F.SilkS" user "Ref Des/Silkscreen Top")
		(7 "B.SilkS" user "Ref Des/Silkscreen Bottom")
		(1 "F.Mask" user "Board Geometry/Soldermask Top")
		(3 "B.Mask" user "Board Geometry/Soldermask Bottom")
		(17 "Dwgs.User" user "User.Drawings")
		(19 "Cmts.User" user "User.Comments")
		(21 "Eco1.User" user "User.Eco1")
		(23 "Eco2.User" user "User.Eco2")
		(25 "Edge.Cuts" user "Board Geometry/Outline")
		(27 "Margin" user)
		(31 "F.CrtYd" user "Package Geometry/Place Bound Top")
		(29 "B.CrtYd" user "Package Geometry/Place Bound Bottom")
		(35 "F.Fab" user "Ref Des/Assembly Top")
		(33 "B.Fab" user "Ref Des/Assembly Bottom")
	)
	(footprint ""
		(layer "F.Cu")
		(at 54.89956 -156.47797 90)
		(property "Reference" "PU50_P1_1"
			(at -0.83312 -13.79728 0)
			(unlocked yes)
			(layer "F.SilkS")
			(effects
				(font
					(size 0.7874 0.5842)
					(thickness 0.1524)
				)
				(justify left)
			)
		)
		(property "Value" ""
			(at 0 0 90)
			(layer "F.Fab")
			(effects
				(font
					(size 1.27 1.27)
				)
			)
		)
		(duplicate_pad_numbers_are_jumpers no)
		(fp_line
			(start 2.500122 -2.999994)
			(end 2.500122 -2.44348)
			(stroke
				(width 0.1524)
				(type default)
			)
			(layer "F.SilkS")
		)
		(fp_line
			(start 2.31394 -2.999994)
			(end 2.500122 -2.999994)
			(stroke
				(width 0.1524)
				(type default)
			)
			(layer "F.SilkS")
		)
		(fp_line
			(start -2.500122 -2.999994)
			(end -2.24409 -2.999994)
			(stroke
				(width 0.1524)
				(type default)
			)
			(layer "F.SilkS")
		)
		(fp_line
			(start -2.500122 -2.529078)
			(end -2.500122 -2.999994)
			(stroke
				(width 0.1524)
				(type default)
			)
			(layer "F.SilkS")
		)
		(fp_line
			(start -2.500122 0.6604)
			(end -2.500122 0.229108)
			(stroke
				(width 0.1524)
				(type default)
			)
			(layer "F.SilkS")
		)
		(fp_line
			(start 2.500122 2.339594)
			(end 2.500122 2.999994)
			(stroke
				(width 0.1524)
				(type default)
			)
			(layer "F.SilkS")
		)
		(fp_line
			(start 2.500122 2.999994)
			(end 2.2987 2.999994)
			(stroke
				(width 0.1524)
				(type default)
			)
			(layer "F.SilkS")
		)
		(fp_line
			(start -2.2987 2.999994)
			(end -2.500122 2.999994)
			(stroke
				(width 0.1524)
				(type default)
			)
			(layer "F.SilkS")
		)
		(fp_line
			(start -2.500122 2.999994)
			(end -2.500122 2.339594)
			(stroke
				(width 0.1524)
				(type default)
			)
			(layer "F.SilkS")
		)
		(fp_poly
			(pts
				(xy -5.109972 -2.793238) (xy -5.109972 -1.777238) (xy -4.093972 -2.285238)
			)
			(stroke
				(width 0)
				(type default)
			)
			(fill yes)
			(layer "F.SilkS")
		)
		(fp_line
			(start 2.500122 -2.999994)
			(end 2.500122 2.999994)
			(stroke
				(width 0.1)
				(type default)
			)
			(layer "F.Fab")
		)
		(fp_line
			(start -2.500122 -2.999994)
			(end 2.500122 -2.999994)
			(stroke
				(width 0.1)
				(type default)
			)
			(layer "F.Fab")
		)
		(fp_line
			(start 2.500122 2.999994)
			(end -2.500122 2.999994)
			(stroke
				(width 0.1)
				(type default)
			)
			(layer "F.Fab")
		)
		(fp_line
			(start -2.500122 2.999994)
			(end -2.500122 -2.999994)
			(stroke
				(width 0.1)
				(type default)
			)
			(layer "F.Fab")
		)
		(fp_poly
			(pts
				(xy -4.218432 -2.783078) (xy -4.218432 -1.767078) (xy -3.202432 -2.275078)
			)
			(stroke
				(width 0)
				(type default)
			)
			(fill yes)
			(layer "F.Fab")
		)
		(pad "1" smd rect
			(at -2.400046 -2.275078 180)
			(size 0.2286 0.6096)
			(layers "F.Cu" "F.Mask" "F.Paste")
			(net "PVCCINFAON_CPU1_VOS1")
		)
		(pad "2" smd rect
			(at -2.400046 -1.82499 180)
			(size 0.2286 0.6096)
			(layers "F.Cu" "F.Mask" "F.Paste")
			(net "GND")
		)
		(pad "3" smd rect
			(at -2.400046 -1.374902 180)
			(size 0.2286 0.6096)
			(layers "F.Cu" "F.Mask" "F.Paste")
			(net "PVCCINFAON_CPU1_VDD1")
		)
		(pad "4" smd rect
			(at -2.400046 -0.925068 180)
			(size 0.2286 0.6096)
			(layers "F.Cu" "F.Mask" "F.Paste")
			(net "PVCCFA_EHV_CPU1_PVCC")
		)
		(pad "5" smd rect
			(at -2.400046 -0.47498 180)
			(size 0.2286 0.6096)
			(layers "F.Cu" "F.Mask" "F.Paste")
			(net "GND")
		)
		(pad "6" smd rect
			(at -2.400046 -0.024892 180)
			(size 0.2286 0.6096)
			(layers "F.Cu" "F.Mask" "F.Paste")
			(net "Net_1929")
		)
		(pad "7_9-20_24" smd circle
			(at 0 1.150112 180)
			(size 0 0)
			(layers "F.Cu" "F.Mask" "F.Paste")
			(net "GND")
		)
		(pad "10_19" smd rect
			(at 0 2.899918 180)
			(size 0.6096 4.318)
			(layers "F.Cu" "F.Mask" "F.Paste")
			(net "SW_PVCCINFAON_CPU1_SW1")
		)
		(pad "25_29" smd rect
			(at 1.549908 -1.279906)
			(size 2.0574 2.3114)
			(layers "F.Cu" "F.Mask" "F.Paste")
			(net "SW_P12V_PVCCINFAON_CPU1_FLT")
		)
		(pad "30" smd rect
			(at 2.05994 -2.899918 90)
			(size 0.2286 0.6096)
			(layers "F.Cu" "F.Mask" "F.Paste")
			(net "SW_P12V_PVCCINFAON_CPU1_FLT")
		)
		(pad "31" smd rect
			(at 1.610106 -2.899918 90)
			(size 0.2286 0.6096)
			(layers "F.Cu" "F.Mask" "F.Paste")
			(net "Net_1928")
		)
		(pad "32" smd rect
			(at 1.160018 -2.899918 90)
			(size 0.2286 0.6096)
			(layers "F.Cu" "F.Mask" "F.Paste")
			(net "SW_PVCCINFAON_CPU1_BOOTR1")
		)
		(pad "33" smd rect
			(at 0.70993 -2.899918 90)
			(size 0.2286 0.6096)
			(layers "F.Cu" "F.Mask" "F.Paste")
			(net "SW_PVCCINFAON_CPU1_BOOT1")
		)
		(pad "34" smd rect
			(at 0.260096 -2.899918 90)
			(size 0.2286 0.6096)
			(layers "F.Cu" "F.Mask" "F.Paste")
			(net "PVCCINFAON_CPU1_APWM1")
		)
		(pad "35" smd rect
			(at -0.189992 -2.899918 90)
			(size 0.2286 0.6096)
			(layers "F.Cu" "F.Mask" "F.Paste")
			(net "PVCCINFAON_CPU1_VDD1")
		)
		(pad "36" smd rect
			(at -0.64008 -2.899918 90)
			(size 0.2286 0.6096)
			(layers "F.Cu" "F.Mask" "F.Paste")
			(net "PVCCINFAON_CPU1_ATSEN")
		)
		(pad "37" smd rect
			(at -1.089914 -2.899918 90)
			(size 0.2286 0.6096)
			(layers "F.Cu" "F.Mask" "F.Paste")
			(net "PVCCINFAON_CPU1_LSET1")
		)
		(pad "38" smd rect
			(at -1.540002 -2.899918 90)
			(size 0.2286 0.6096)
			(layers "F.Cu" "F.Mask" "F.Paste")
			(net "PVCCINFAON_CPU1_ACSP1")
		)
		(pad "39" smd rect
			(at -1.99009 -2.899918 90)
			(size 0.2286 0.6096)
			(layers "F.Cu" "F.Mask" "F.Paste")
			(net "PVCCINFAON_CPU1_VREF")
		)
		(pad "40" smd rect
			(at -0.87503 -1.27508 90)
			(size 1.7526 1.9558)
			(layers "F.Cu" "F.Mask" "F.Paste")
			(net "GND")
		)
		(pad "41" smd rect
			(at -1.525016 0.249936)
			(size 0.3048 0.4572)
			(layers "F.Cu" "F.Mask" "F.Paste")
			(net "Net_1930")
		)
		(zone
			(layer "F.Cu")
			(hatch none 0.5)
			(connect_pads
				(clearance 0)
			)
			(min_thickness 0.25)
			(keepout
				(tracks not_allowed)
				(vias allowed)
				(pads allowed)
				(copperpour not_allowed)
				(footprints allowed)
			)
			(placement
				(enabled no)
				(sheetname "")
			)
			(fill
				(thermal_gap 0.5)
				(thermal_bridge_width 0.5)
				(island_removal_mode 0)
			)
			(polygon
				(pts
					(xy 57.899554 -153.977848) (xy 57.391046 -153.977848) (xy 57.150254 -154.21864) (xy 57.150254 -158.767526)
					(xy 57.36082 -158.978092) (xy 57.899554 -158.978092) (xy 57.899554 -158.68777) (xy 57.443878 -158.68777)
					(xy 57.443878 -154.26817) (xy 57.899554 -154.26817)
				)
			)
		)
	)
)
